(kicad_pcb
	(version 20221018)
	(generator pcbnew)
	(general
    (thickness 1.62)
  )
	(paper "A4")
	(title_block
    (title "ECP5 - Datacenter Secure Control Module (DC-SCM)")
    (date "2024-07-01")
    (rev "1.2.1")
		(comment 9 "footprints 288-295 of 506")
	)
	(layers
    (0 "F.Cu" signal)
    (1 "In1.Cu" power)
    (2 "In2.Cu" signal)
    (3 "In3.Cu" power)
    (4 "In4.Cu" power)
    (5 "In5.Cu" signal)
    (6 "In6.Cu" power)
    (31 "B.Cu" signal)
    (32 "B.Adhes" user "B.Adhesive")
    (33 "F.Adhes" user "F.Adhesive")
    (34 "B.Paste" user)
    (35 "F.Paste" user)
    (36 "B.SilkS" user "B.Silkscreen")
    (37 "F.SilkS" user "F.Silkscreen")
    (38 "B.Mask" user)
    (39 "F.Mask" user)
    (40 "Dwgs.User" user "User.Drawings")
    (41 "Cmts.User" user "User.Comments")
    (42 "Eco1.User" user "User.Eco1")
    (43 "Eco2.User" user "User.Eco2")
    (44 "Edge.Cuts" user)
    (45 "Margin" user)
    (46 "B.CrtYd" user "B.Courtyard")
    (47 "F.CrtYd" user "F.Courtyard")
    (48 "B.Fab" user)
    (49 "F.Fab" user)
  )
	(footprint "antmicro-footprints:C_0402_1005Metric" (layer "B.Cu")
    (at 107.95 113.75 -90)
    (descr "Capacitor SMD 0402")
    (tags "capacitor SMD 0402")
    (property "Author" "Antmicro")
    (property "Dielectric" "")
    (property "License" "Apache-2.0")
    (property "MPN" "C1005X5R1E474M050BB")
    (property "Manufacturer" "TDK")
    (property "Public" "False")
    (property "Sheetfile" "fpga-power-supply.kicad_sch")
    (property "Sheetname" "FPGA power supply")
    (property "Val" "470n")
    (property "Voltage" "")
    (property "ki_description" "SMD Multilayer Ceramic Capacitor, 0.47 µF, 25 V, 0402 [1005 Metric], ± 20%, X5R, C")
    (property "ki_keywords" "0402, SMT, CAPACITOR, PASSIVE, CERAMIC, MLCC")
    (attr smd)
    (fp_text reference "C167" (at -2.325 -0.57 90) (layer "B.SilkS")
        (effects (font (size 0.7 0.7) (thickness 0.127)) (justify mirror))
    )
    (fp_text value "C_470n_0402" (at 0 -1.17 90) (layer "B.Fab")
        (effects (font (size 1 1) (thickness 0.15)) (justify mirror))
    )
    (fp_text user "${REFERENCE}" (at 0 0 90) (layer "B.Fab")
        (effects (font (size 0.25 0.25) (thickness 0.04)) (justify mirror))
    )
    (fp_text user "Author: Antmicro" (at -0.939 -3.399 90) (layer "B.Fab") hide
        (effects (font (size 0.7 0.7) (thickness 0.15)) (justify left bottom mirror))
    )
    (fp_text user "License: Apache-2.0" (at -0.939 -5.799 90) (layer "B.Fab") hide
        (effects (font (size 0.7 0.7) (thickness 0.15)) (justify left bottom mirror))
    )
    (fp_rect (start -0.925 0.47) (end 0.925 -0.47)
      (stroke (width 0.05) (type default)) (fill none) (layer "B.CrtYd"))
    (fp_line (start -0.494 -0.248) (end -0.494 0.25)
      (stroke (width 0.15) (type solid)) (layer "B.Fab"))
    (fp_line (start -0.494 0.25) (end 0.504 0.25)
      (stroke (width 0.15) (type solid)) (layer "B.Fab"))
    (fp_line (start 0.504 -0.248) (end -0.494 -0.248)
      (stroke (width 0.15) (type solid)) (layer "B.Fab"))
    (fp_line (start 0.504 0.25) (end 0.504 -0.248)
      (stroke (width 0.15) (type solid)) (layer "B.Fab"))
    (pad "1" smd roundrect (at -0.48 0 270) (size 0.59 0.64) (layers "B.Cu" "B.Paste" "B.Mask") (roundrect_rratio 0.25)
      (net 1 "GND") (pintype "passive"))
    (pad "2" smd roundrect (at 0.48 0 270) (size 0.59 0.64) (layers "B.Cu" "B.Paste" "B.Mask") (roundrect_rratio 0.25)
      (net 304 "/FPGA power supply/VCCAUX") (pintype "passive"))
  )
	(footprint "antmicro-footprints:C_0402_1005Metric" (layer "B.Cu")
    (at 107.1 118.85 180)
    (descr "Capacitor SMD 0402")
    (tags "capacitor SMD 0402")
    (property "Author" "Antmicro")
    (property "Dielectric" "")
    (property "License" "Apache-2.0")
    (property "MPN" "C1005X5R1E474M050BB")
    (property "Manufacturer" "TDK")
    (property "Public" "False")
    (property "Sheetfile" "fpga-power-supply.kicad_sch")
    (property "Sheetname" "FPGA power supply")
    (property "Val" "470n")
    (property "Voltage" "")
    (property "ki_description" "SMD Multilayer Ceramic Capacitor, 0.47 µF, 25 V, 0402 [1005 Metric], ± 20%, X5R, C")
    (property "ki_keywords" "0402, SMT, CAPACITOR, PASSIVE, CERAMIC, MLCC")
    (attr smd)
    (fp_text reference "C168" (at 0.55 -22.85) (layer "B.SilkS")
        (effects (font (size 0.7 0.7) (thickness 0.127)) (justify mirror))
    )
    (fp_text value "C_470n_0402" (at 0 -1.17) (layer "B.Fab")
        (effects (font (size 1 1) (thickness 0.15)) (justify mirror))
    )
    (fp_text user "Author: Antmicro" (at -0.939 -3.399) (layer "B.Fab") hide
        (effects (font (size 0.7 0.7) (thickness 0.15)) (justify left bottom mirror))
    )
    (fp_text user "License: Apache-2.0" (at -0.939 -5.799) (layer "B.Fab") hide
        (effects (font (size 0.7 0.7) (thickness 0.15)) (justify left bottom mirror))
    )
    (fp_text user "${REFERENCE}" (at 0 0) (layer "B.Fab")
        (effects (font (size 0.25 0.25) (thickness 0.04)) (justify mirror))
    )
    (fp_rect (start -0.925 0.47) (end 0.925 -0.47)
      (stroke (width 0.05) (type default)) (fill none) (layer "B.CrtYd"))
    (fp_line (start -0.494 -0.248) (end -0.494 0.25)
      (stroke (width 0.15) (type solid)) (layer "B.Fab"))
    (fp_line (start -0.494 0.25) (end 0.504 0.25)
      (stroke (width 0.15) (type solid)) (layer "B.Fab"))
    (fp_line (start 0.504 -0.248) (end -0.494 -0.248)
      (stroke (width 0.15) (type solid)) (layer "B.Fab"))
    (fp_line (start 0.504 0.25) (end 0.504 -0.248)
      (stroke (width 0.15) (type solid)) (layer "B.Fab"))
    (pad "1" smd roundrect (at -0.48 0 180) (size 0.59 0.64) (layers "B.Cu" "B.Paste" "B.Mask") (roundrect_rratio 0.25)
      (net 211 "VCC1V2") (pintype "passive"))
    (pad "2" smd roundrect (at 0.48 0 180) (size 0.59 0.64) (layers "B.Cu" "B.Paste" "B.Mask") (roundrect_rratio 0.25)
      (net 1 "GND") (pintype "passive"))
  )
	(footprint "antmicro-footprints:C_0402_1005Metric" (layer "B.Cu")
    (at 107.95 129.2)
    (descr "Capacitor SMD 0402")
    (tags "capacitor SMD 0402")
    (property "Author" "Antmicro")
    (property "Dielectric" "X5R")
    (property "License" "Apache-2.0")
    (property "MPN" "GRM155R61H104KE14D")
    (property "Manufacturer" "Murata")
    (property "Public" "False")
    (property "Sheetfile" "fpga-power-supply.kicad_sch")
    (property "Sheetname" "FPGA power supply")
    (property "Val" "100n")
    (property "Voltage" "50V")
    (property "ki_description" "SMD Multilayer Ceramic Capacitor, 0.1 µF, 50 V, 0402 [1005 Metric], ± 10%, X5R, GRM Series")
    (property "ki_keywords" "0402, SMT, CAPACITOR, PASSIVE, CERAMIC, MLCC")
    (attr smd)
    (fp_text reference "C169" (at 0.71 20.785) (layer "B.SilkS")
        (effects (font (size 0.7 0.7) (thickness 0.127)) (justify mirror))
    )
    (fp_text value "C_100n_0402" (at 0 -1.17) (layer "B.Fab")
        (effects (font (size 1 1) (thickness 0.15)) (justify mirror))
    )
    (fp_text user "${REFERENCE}" (at 0 0) (layer "B.Fab")
        (effects (font (size 0.25 0.25) (thickness 0.04)) (justify mirror))
    )
    (fp_text user "Author: Antmicro" (at -0.939 -3.399 180) (layer "B.Fab") hide
        (effects (font (size 0.7 0.7) (thickness 0.15)) (justify left bottom mirror))
    )
    (fp_text user "License: Apache-2.0" (at -0.939 -5.799 180) (layer "B.Fab") hide
        (effects (font (size 0.7 0.7) (thickness 0.15)) (justify left bottom mirror))
    )
    (fp_rect (start -0.925 0.47) (end 0.925 -0.47)
      (stroke (width 0.05) (type default)) (fill none) (layer "B.CrtYd"))
    (fp_line (start -0.494 -0.248) (end -0.494 0.25)
      (stroke (width 0.15) (type solid)) (layer "B.Fab"))
    (fp_line (start -0.494 0.25) (end 0.504 0.25)
      (stroke (width 0.15) (type solid)) (layer "B.Fab"))
    (fp_line (start 0.504 -0.248) (end -0.494 -0.248)
      (stroke (width 0.15) (type solid)) (layer "B.Fab"))
    (fp_line (start 0.504 0.25) (end 0.504 -0.248)
      (stroke (width 0.15) (type solid)) (layer "B.Fab"))
    (pad "1" smd roundrect (at -0.48 0) (size 0.59 0.64) (layers "B.Cu" "B.Paste" "B.Mask") (roundrect_rratio 0.25)
      (net 1 "GND") (pintype "passive"))
    (pad "2" smd roundrect (at 0.48 0) (size 0.59 0.64) (layers "B.Cu" "B.Paste" "B.Mask") (roundrect_rratio 0.25)
      (net 303 "/FPGA power supply/VCCA1") (pintype "passive"))
  )
	(footprint "antmicro-footprints:C_0402_1005Metric" (layer "B.Cu")
    (at 111.2 117.1 180)
    (descr "Capacitor SMD 0402")
    (tags "capacitor SMD 0402")
    (property "Author" "Antmicro")
    (property "Dielectric" "")
    (property "License" "Apache-2.0")
    (property "MPN" "C1005X5R1E474M050BB")
    (property "Manufacturer" "TDK")
    (property "Public" "False")
    (property "Sheetfile" "fpga-power-supply.kicad_sch")
    (property "Sheetname" "FPGA power supply")
    (property "Val" "470n")
    (property "Voltage" "")
    (property "ki_description" "SMD Multilayer Ceramic Capacitor, 0.47 µF, 25 V, 0402 [1005 Metric], ± 20%, X5R, C")
    (property "ki_keywords" "0402, SMT, CAPACITOR, PASSIVE, CERAMIC, MLCC")
    (attr smd)
    (fp_text reference "C170" (at -2.57 -0.075) (layer "B.SilkS")
        (effects (font (size 0.7 0.7) (thickness 0.127)) (justify mirror))
    )
    (fp_text value "C_470n_0402" (at 0 -1.17) (layer "B.Fab")
        (effects (font (size 1 1) (thickness 0.15)) (justify mirror))
    )
    (fp_text user "${REFERENCE}" (at 0 0) (layer "B.Fab")
        (effects (font (size 0.25 0.25) (thickness 0.04)) (justify mirror))
    )
    (fp_text user "License: Apache-2.0" (at -0.939 -5.799) (layer "B.Fab") hide
        (effects (font (size 0.7 0.7) (thickness 0.15)) (justify left bottom mirror))
    )
    (fp_text user "Author: Antmicro" (at -0.939 -3.399) (layer "B.Fab") hide
        (effects (font (size 0.7 0.7) (thickness 0.15)) (justify left bottom mirror))
    )
    (fp_rect (start -0.925 0.47) (end 0.925 -0.47)
      (stroke (width 0.05) (type default)) (fill none) (layer "B.CrtYd"))
    (fp_line (start -0.494 -0.248) (end -0.494 0.25)
      (stroke (width 0.15) (type solid)) (layer "B.Fab"))
    (fp_line (start -0.494 0.25) (end 0.504 0.25)
      (stroke (width 0.15) (type solid)) (layer "B.Fab"))
    (fp_line (start 0.504 -0.248) (end -0.494 -0.248)
      (stroke (width 0.15) (type solid)) (layer "B.Fab"))
    (fp_line (start 0.504 0.25) (end 0.504 -0.248)
      (stroke (width 0.15) (type solid)) (layer "B.Fab"))
    (pad "1" smd roundrect (at -0.48 0 180) (size 0.59 0.64) (layers "B.Cu" "B.Paste" "B.Mask") (roundrect_rratio 0.25)
      (net 1 "GND") (pintype "passive"))
    (pad "2" smd roundrect (at 0.48 0 180) (size 0.59 0.64) (layers "B.Cu" "B.Paste" "B.Mask") (roundrect_rratio 0.25)
      (net 304 "/FPGA power supply/VCCAUX") (pintype "passive"))
  )
	(footprint "antmicro-footprints:C_0402_1005Metric" (layer "B.Cu")
    (at 108.35 116.55 -90)
    (descr "Capacitor SMD 0402")
    (tags "capacitor SMD 0402")
    (property "Author" "Antmicro")
    (property "Dielectric" "")
    (property "License" "Apache-2.0")
    (property "MPN" "C1005X5R1E474M050BB")
    (property "Manufacturer" "TDK")
    (property "Public" "False")
    (property "Sheetfile" "fpga-power-supply.kicad_sch")
    (property "Sheetname" "FPGA power supply")
    (property "Val" "470n")
    (property "Voltage" "")
    (property "ki_description" "SMD Multilayer Ceramic Capacitor, 0.47 µF, 25 V, 0402 [1005 Metric], ± 20%, X5R, C")
    (property "ki_keywords" "0402, SMT, CAPACITOR, PASSIVE, CERAMIC, MLCC")
    (attr smd)
    (fp_text reference "C171" (at 22.6 -0.1 90) (layer "B.SilkS")
        (effects (font (size 0.7 0.7) (thickness 0.127)) (justify mirror))
    )
    (fp_text value "C_470n_0402" (at 0 -1.17 90) (layer "B.Fab")
        (effects (font (size 1 1) (thickness 0.15)) (justify mirror))
    )
    (fp_text user "${REFERENCE}" (at 0 0 90) (layer "B.Fab")
        (effects (font (size 0.25 0.25) (thickness 0.04)) (justify mirror))
    )
    (fp_text user "License: Apache-2.0" (at -0.939 -5.799 90) (layer "B.Fab") hide
        (effects (font (size 0.7 0.7) (thickness 0.15)) (justify left bottom mirror))
    )
    (fp_text user "Author: Antmicro" (at -0.939 -3.399 90) (layer "B.Fab") hide
        (effects (font (size 0.7 0.7) (thickness 0.15)) (justify left bottom mirror))
    )
    (fp_rect (start -0.925 0.47) (end 0.925 -0.47)
      (stroke (width 0.05) (type default)) (fill none) (layer "B.CrtYd"))
    (fp_line (start -0.494 -0.248) (end -0.494 0.25)
      (stroke (width 0.15) (type solid)) (layer "B.Fab"))
    (fp_line (start -0.494 0.25) (end 0.504 0.25)
      (stroke (width 0.15) (type solid)) (layer "B.Fab"))
    (fp_line (start 0.504 -0.248) (end -0.494 -0.248)
      (stroke (width 0.15) (type solid)) (layer "B.Fab"))
    (fp_line (start 0.504 0.25) (end 0.504 -0.248)
      (stroke (width 0.15) (type solid)) (layer "B.Fab"))
    (pad "1" smd roundrect (at -0.48 0 270) (size 0.59 0.64) (layers "B.Cu" "B.Paste" "B.Mask") (roundrect_rratio 0.25)
      (net 211 "VCC1V2") (pintype "passive"))
    (pad "2" smd roundrect (at 0.48 0 270) (size 0.59 0.64) (layers "B.Cu" "B.Paste" "B.Mask") (roundrect_rratio 0.25)
      (net 1 "GND") (pintype "passive"))
  )
	(footprint "antmicro-footprints:C_0402_1005Metric" (layer "B.Cu")
    (at 105 132.25 90)
    (descr "Capacitor SMD 0402")
    (tags "capacitor SMD 0402")
    (property "Author" "Antmicro")
    (property "Dielectric" "X7R")
    (property "License" "Apache-2.0")
    (property "MPN" "GRM155R71H103KA88D")
    (property "Manufacturer" "Murata")
    (property "Public" "False")
    (property "Sheetfile" "fpga-power-supply.kicad_sch")
    (property "Sheetname" "FPGA power supply")
    (property "Val" "10n")
    (property "Voltage" "50V")
    (property "ki_description" "SMD Multilayer Ceramic Capacitor, 10000 pF, 50 V, 0402 [1005 Metric], ± 10%, X7R, GRM Series")
    (property "ki_keywords" "0402, SMT, CAPACITOR, PASSIVE")
    (attr smd)
    (fp_text reference "C172" (at -20.825 0.89 90) (layer "B.SilkS")
        (effects (font (size 0.7 0.7) (thickness 0.127)) (justify mirror))
    )
    (fp_text value "C_10n_0402" (at 0 -1.17 90) (layer "B.Fab")
        (effects (font (size 1 1) (thickness 0.15)) (justify mirror))
    )
    (fp_text user "License: Apache-2.0" (at -0.939 -5.799 270) (layer "B.Fab") hide
        (effects (font (size 0.7 0.7) (thickness 0.15)) (justify left bottom mirror))
    )
    (fp_text user "${REFERENCE}" (at 0 0 90) (layer "B.Fab")
        (effects (font (size 0.25 0.25) (thickness 0.04)) (justify mirror))
    )
    (fp_text user "Author: Antmicro" (at -0.939 -3.399 270) (layer "B.Fab") hide
        (effects (font (size 0.7 0.7) (thickness 0.15)) (justify left bottom mirror))
    )
    (fp_rect (start -0.925 0.47) (end 0.925 -0.47)
      (stroke (width 0.05) (type default)) (fill none) (layer "B.CrtYd"))
    (fp_line (start -0.494 -0.248) (end -0.494 0.25)
      (stroke (width 0.15) (type solid)) (layer "B.Fab"))
    (fp_line (start -0.494 0.25) (end 0.504 0.25)
      (stroke (width 0.15) (type solid)) (layer "B.Fab"))
    (fp_line (start 0.504 -0.248) (end -0.494 -0.248)
      (stroke (width 0.15) (type solid)) (layer "B.Fab"))
    (fp_line (start 0.504 0.25) (end 0.504 -0.248)
      (stroke (width 0.15) (type solid)) (layer "B.Fab"))
    (pad "1" smd roundrect (at -0.48 0 90) (size 0.59 0.64) (layers "B.Cu" "B.Paste" "B.Mask") (roundrect_rratio 0.25)
      (net 1 "GND") (pintype "passive"))
    (pad "2" smd roundrect (at 0.48 0 90) (size 0.59 0.64) (layers "B.Cu" "B.Paste" "B.Mask") (roundrect_rratio 0.25)
      (net 303 "/FPGA power supply/VCCA1") (pintype "passive"))
  )
	(footprint "antmicro-footprints:C_0402_1005Metric" (layer "B.Cu")
    (at 111.25 122.725 180)
    (descr "Capacitor SMD 0402")
    (tags "capacitor SMD 0402")
    (property "Author" "Antmicro")
    (property "Dielectric" "")
    (property "License" "Apache-2.0")
    (property "MPN" "C1005X5R1E474M050BB")
    (property "Manufacturer" "TDK")
    (property "Public" "False")
    (property "Sheetfile" "fpga-power-supply.kicad_sch")
    (property "Sheetname" "FPGA power supply")
    (property "Val" "470n")
    (property "Voltage" "")
    (property "ki_description" "SMD Multilayer Ceramic Capacitor, 0.47 µF, 25 V, 0402 [1005 Metric], ± 20%, X5R, C")
    (property "ki_keywords" "0402, SMT, CAPACITOR, PASSIVE, CERAMIC, MLCC")
    (attr smd)
    (fp_text reference "C173" (at -2.58 -0.07) (layer "B.SilkS")
        (effects (font (size 0.7 0.7) (thickness 0.127)) (justify mirror))
    )
    (fp_text value "C_470n_0402" (at 0 -1.17) (layer "B.Fab")
        (effects (font (size 1 1) (thickness 0.15)) (justify mirror))
    )
    (fp_text user "${REFERENCE}" (at 0 0) (layer "B.Fab")
        (effects (font (size 0.25 0.25) (thickness 0.04)) (justify mirror))
    )
    (fp_text user "License: Apache-2.0" (at -0.939 -5.799) (layer "B.Fab") hide
        (effects (font (size 0.7 0.7) (thickness 0.15)) (justify left bottom mirror))
    )
    (fp_text user "Author: Antmicro" (at -0.939 -3.399) (layer "B.Fab") hide
        (effects (font (size 0.7 0.7) (thickness 0.15)) (justify left bottom mirror))
    )
    (fp_rect (start -0.925 0.47) (end 0.925 -0.47)
      (stroke (width 0.05) (type default)) (fill none) (layer "B.CrtYd"))
    (fp_line (start -0.494 -0.248) (end -0.494 0.25)
      (stroke (width 0.15) (type solid)) (layer "B.Fab"))
    (fp_line (start -0.494 0.25) (end 0.504 0.25)
      (stroke (width 0.15) (type solid)) (layer "B.Fab"))
    (fp_line (start 0.504 -0.248) (end -0.494 -0.248)
      (stroke (width 0.15) (type solid)) (layer "B.Fab"))
    (fp_line (start 0.504 0.25) (end 0.504 -0.248)
      (stroke (width 0.15) (type solid)) (layer "B.Fab"))
    (pad "1" smd roundrect (at -0.48 0 180) (size 0.59 0.64) (layers "B.Cu" "B.Paste" "B.Mask") (roundrect_rratio 0.25)
      (net 1 "GND") (pintype "passive"))
    (pad "2" smd roundrect (at 0.48 0 180) (size 0.59 0.64) (layers "B.Cu" "B.Paste" "B.Mask") (roundrect_rratio 0.25)
      (net 304 "/FPGA power supply/VCCAUX") (pintype "passive"))
  )
	(footprint "antmicro-footprints:C_0402_1005Metric" (layer "B.Cu")
    (at 106.85 124.05 90)
    (descr "Capacitor SMD 0402")
    (tags "capacitor SMD 0402")
    (property "Author" "Antmicro")
    (property "Dielectric" "")
    (property "License" "Apache-2.0")
    (property "MPN" "C1005X5R1E474M050BB")
    (property "Manufacturer" "TDK")
    (property "Public" "False")
    (property "Sheetfile" "fpga-power-supply.kicad_sch")
    (property "Sheetname" "FPGA power supply")
    (property "Val" "470n")
    (property "Voltage" "")
    (property "ki_description" "SMD Multilayer Ceramic Capacitor, 0.47 µF, 25 V, 0402 [1005 Metric], ± 20%, X5R, C")
    (property "ki_keywords" "0402, SMT, CAPACITOR, PASSIVE, CERAMIC, MLCC")
    (attr smd)
    (fp_text reference "C174" (at -22.165 -0.02 90) (layer "B.SilkS")
        (effects (font (size 0.7 0.7) (thickness 0.127)) (justify mirror))
    )
    (fp_text value "C_470n_0402" (at 0 -1.17 90) (layer "B.Fab")
        (effects (font (size 1 1) (thickness 0.15)) (justify mirror))
    )
    (fp_text user "License: Apache-2.0" (at -0.939 -5.799 270) (layer "B.Fab") hide
        (effects (font (size 0.7 0.7) (thickness 0.15)) (justify left bottom mirror))
    )
    (fp_text user "${REFERENCE}" (at 0 0 90) (layer "B.Fab")
        (effects (font (size 0.25 0.25) (thickness 0.04)) (justify mirror))
    )
    (fp_text user "Author: Antmicro" (at -0.939 -3.399 270) (layer "B.Fab") hide
        (effects (font (size 0.7 0.7) (thickness 0.15)) (justify left bottom mirror))
    )
    (fp_rect (start -0.925 0.47) (end 0.925 -0.47)
      (stroke (width 0.05) (type default)) (fill none) (layer "B.CrtYd"))
    (fp_line (start -0.494 -0.248) (end -0.494 0.25)
      (stroke (width 0.15) (type solid)) (layer "B.Fab"))
    (fp_line (start -0.494 0.25) (end 0.504 0.25)
      (stroke (width 0.15) (type solid)) (layer "B.Fab"))
    (fp_line (start 0.504 -0.248) (end -0.494 -0.248)
      (stroke (width 0.15) (type solid)) (layer "B.Fab"))
    (fp_line (start 0.504 0.25) (end 0.504 -0.248)
      (stroke (width 0.15) (type solid)) (layer "B.Fab"))
    (pad "1" smd roundrect (at -0.48 0 90) (size 0.59 0.64) (layers "B.Cu" "B.Paste" "B.Mask") (roundrect_rratio 0.25)
      (net 211 "VCC1V2") (pintype "passive"))
    (pad "2" smd roundrect (at 0.48 0 90) (size 0.59 0.64) (layers "B.Cu" "B.Paste" "B.Mask") (roundrect_rratio 0.25)
      (net 1 "GND") (pintype "passive"))
  )
)
